(kicad_pcb
	(version 20260206)
	(generator "pcbnew")
	(generator_version "10.0")
	(general
		(thickness 1.6)
		(legacy_teardrops no)
	)
	(paper "A4")
	(title_block
		(title "fcb — 12433-1M.1206WZS1330.brd")
		(comment 1 "Open Vault / Knox (Wiwynn) / footprints 473-480 of 495")
	)
	(layers
		(0 "F.Cu" signal "TOP")
		(4 "In1.Cu" signal "L2GND")
		(6 "In2.Cu" signal "L3VCC")
		(2 "B.Cu" signal "BOTTOM")
		(9 "F.Adhes" user "F.Adhesive")
		(11 "B.Adhes" user "B.Adhesive")
		(13 "F.Paste" user "Package Geometry/Pastemask Top")
		(15 "B.Paste" user "Package Geometry/Pastemask Bottom")
		(5 "F.SilkS" user "Ref Des/Silkscreen Top")
		(7 "B.SilkS" user "Ref Des/Silkscreen Bottom")
		(1 "F.Mask" user "Board Geometry/Soldermask Top")
		(3 "B.Mask" user "Board Geometry/Soldermask Bottom")
		(17 "Dwgs.User" user "User.Drawings")
		(19 "Cmts.User" user "User.Comments")
		(21 "Eco1.User" user "User.Eco1")
		(23 "Eco2.User" user "User.Eco2")
		(25 "Edge.Cuts" user "Board Geometry/Outline")
		(27 "Margin" user)
		(31 "F.CrtYd" user "Package Geometry/Place Bound Top")
		(29 "B.CrtYd" user "Package Geometry/Place Bound Bottom")
		(35 "F.Fab" user "Ref Des/Assembly Top")
		(33 "B.Fab" user "Ref Des/Assembly Bottom")
	)
	(footprint ""
		(layer "F.Cu")
		(at 34.29 -358.166416)
		(property "Reference" "R364"
			(at 0 0 0)
			(layer "F.SilkS")
			(hide yes)
			(effects
				(font
					(size 1.27 1.27)
				)
			)
		)
		(property "Value" "0R2J-2-GP"
			(at 0.064008 -3.993896 0)
			(unlocked yes)
			(layer "F.Fab")
			(hide yes)
			(effects
				(font
					(size 1.016 1.016)
					(thickness 0.1524)
				)
			)
		)
		(property "Device Type" "R402H16"
			(at 0.064008 -5.517896 0)
			(unlocked yes)
			(layer "F.Fab")
			(hide yes)
			(effects
				(font
					(size 1.016 1.016)
					(thickness 0.1524)
				)
			)
		)
		(duplicate_pad_numbers_are_jumpers no)
		(fp_line
			(start -0.508 -0.9398)
			(end -0.508 0.9398)
			(stroke
				(width 0.1524)
				(type default)
			)
			(layer "F.SilkS")
		)
		(fp_line
			(start 0.508 -0.9398)
			(end -0.508 -0.9398)
			(stroke
				(width 0.1524)
				(type default)
			)
			(layer "F.SilkS")
		)
		(fp_rect
			(start -0.508 0.9398)
			(end 0.508 -0.9398)
			(stroke
				(width 0)
				(type default)
			)
			(fill no)
			(layer "F.CrtYd")
		)
		(fp_rect
			(start -0.508 0.9398)
			(end 0.508 -0.9398)
			(stroke
				(width 0)
				(type default)
			)
			(fill no)
			(layer "F.Fab")
		)
		(pad "1" smd custom
			(at 0 -0.4445)
			(size 0.1397 0.1397)
			(layers "F.Cu" "F.Mask" "F.Paste")
			(net "OTP_RETRY_DIODE")
			(options
				(clearance outline)
				(anchor circle)
			)
			(primitives
				(gr_poly
					(pts
						(arc
							(start -0.1778 -0.2794)
							(mid -0.249642 -0.249642)
							(end -0.2794 -0.1778)
						)
						(arc
							(start -0.2794 0.1778)
							(mid -0.249642 0.249642)
							(end -0.1778 0.2794)
						)
						(arc
							(start 0.1778 0.2794)
							(mid 0.249642 0.249642)
							(end 0.2794 0.1778)
						)
						(arc
							(start 0.2794 -0.1778)
							(mid 0.249642 -0.249642)
							(end 0.1778 -0.2794)
						)
					)
					(width 0)
					(fill yes)
				)
			)
		)
		(pad "2" smd custom
			(at 0 0.4445)
			(size 0.1397 0.1397)
			(layers "F.Cu" "F.Mask" "F.Paste")
			(net "OTP_RETRY_G")
			(options
				(clearance outline)
				(anchor circle)
			)
			(primitives
				(gr_poly
					(pts
						(arc
							(start -0.1778 -0.2794)
							(mid -0.249642 -0.249642)
							(end -0.2794 -0.1778)
						)
						(arc
							(start -0.2794 0.1778)
							(mid -0.249642 0.249642)
							(end -0.1778 0.2794)
						)
						(arc
							(start 0.1778 0.2794)
							(mid 0.249642 0.249642)
							(end 0.2794 0.1778)
						)
						(arc
							(start 0.2794 -0.1778)
							(mid 0.249642 -0.249642)
							(end 0.1778 -0.2794)
						)
					)
					(width 0)
					(fill yes)
				)
			)
		)
	)
	(footprint ""
		(layer "F.Cu")
		(at 16.002 -67.564)
		(property "Reference" "R60"
			(at 0 0 0)
			(layer "F.SilkS")
			(hide yes)
			(effects
				(font
					(size 1.27 1.27)
				)
			)
		)
		(property "Value" "4K7R2F-GP"
			(at 0.064008 -3.993896 0)
			(unlocked yes)
			(layer "F.Fab")
			(hide yes)
			(effects
				(font
					(size 1.016 1.016)
					(thickness 0.1524)
				)
			)
		)
		(property "Device Type" "R402H16"
			(at 0.064008 -5.517896 0)
			(unlocked yes)
			(layer "F.Fab")
			(hide yes)
			(effects
				(font
					(size 1.016 1.016)
					(thickness 0.1524)
				)
			)
		)
		(duplicate_pad_numbers_are_jumpers no)
		(fp_line
			(start -0.508 -0.9398)
			(end -0.508 0.9398)
			(stroke
				(width 0.1524)
				(type default)
			)
			(layer "F.SilkS")
		)
		(fp_line
			(start 0.508 -0.9398)
			(end -0.508 -0.9398)
			(stroke
				(width 0.1524)
				(type default)
			)
			(layer "F.SilkS")
		)
		(fp_rect
			(start -0.508 0.9398)
			(end 0.508 -0.9398)
			(stroke
				(width 0)
				(type default)
			)
			(fill no)
			(layer "F.CrtYd")
		)
		(fp_rect
			(start -0.508 0.9398)
			(end 0.508 -0.9398)
			(stroke
				(width 0)
				(type default)
			)
			(fill no)
			(layer "F.Fab")
		)
		(pad "1" smd custom
			(at 0 -0.4445)
			(size 0.1397 0.1397)
			(layers "F.Cu" "F.Mask" "F.Paste")
			(net "P3V3")
			(options
				(clearance outline)
				(anchor circle)
			)
			(primitives
				(gr_poly
					(pts
						(arc
							(start -0.1778 -0.2794)
							(mid -0.249642 -0.249642)
							(end -0.2794 -0.1778)
						)
						(arc
							(start -0.2794 0.1778)
							(mid -0.249642 0.249642)
							(end -0.1778 0.2794)
						)
						(arc
							(start 0.1778 0.2794)
							(mid 0.249642 0.249642)
							(end 0.2794 0.1778)
						)
						(arc
							(start 0.2794 -0.1778)
							(mid 0.249642 -0.249642)
							(end 0.1778 -0.2794)
						)
					)
					(width 0)
					(fill yes)
				)
			)
		)
		(pad "2" smd custom
			(at 0 0.4445)
			(size 0.1397 0.1397)
			(layers "F.Cu" "F.Mask" "F.Paste")
			(net "I2C_C_SDA_CONN_R")
			(options
				(clearance outline)
				(anchor circle)
			)
			(primitives
				(gr_poly
					(pts
						(arc
							(start -0.1778 -0.2794)
							(mid -0.249642 -0.249642)
							(end -0.2794 -0.1778)
						)
						(arc
							(start -0.2794 0.1778)
							(mid -0.249642 0.249642)
							(end -0.1778 0.2794)
						)
						(arc
							(start 0.1778 0.2794)
							(mid 0.249642 0.249642)
							(end 0.2794 0.1778)
						)
						(arc
							(start 0.2794 -0.1778)
							(mid 0.249642 -0.249642)
							(end 0.1778 -0.2794)
						)
					)
					(width 0)
					(fill yes)
				)
			)
		)
	)
	(footprint ""
		(layer "F.Cu")
		(at 14.5796 -53.2384)
		(property "Reference" "R360"
			(at 0 0 0)
			(layer "F.SilkS")
			(hide yes)
			(effects
				(font
					(size 1.27 1.27)
				)
			)
		)
		(property "Value" "100R2J-2-GP"
			(at 0.064008 -3.993896 0)
			(unlocked yes)
			(layer "F.Fab")
			(hide yes)
			(effects
				(font
					(size 1.016 1.016)
					(thickness 0.1524)
				)
			)
		)
		(property "Device Type" "R402H14"
			(at 0.064008 -5.517896 0)
			(unlocked yes)
			(layer "F.Fab")
			(hide yes)
			(effects
				(font
					(size 1.016 1.016)
					(thickness 0.1524)
				)
			)
		)
		(duplicate_pad_numbers_are_jumpers no)
		(fp_line
			(start -0.508 -0.9398)
			(end -0.508 0.9398)
			(stroke
				(width 0.1524)
				(type default)
			)
			(layer "F.SilkS")
		)
		(fp_line
			(start 0.508 -0.9398)
			(end -0.508 -0.9398)
			(stroke
				(width 0.1524)
				(type default)
			)
			(layer "F.SilkS")
		)
		(fp_rect
			(start -0.508 0.9398)
			(end 0.508 -0.9398)
			(stroke
				(width 0)
				(type default)
			)
			(fill no)
			(layer "F.CrtYd")
		)
		(fp_rect
			(start -0.508 0.9398)
			(end 0.508 -0.9398)
			(stroke
				(width 0)
				(type default)
			)
			(fill no)
			(layer "F.Fab")
		)
		(pad "1" smd custom
			(at 0 -0.4445)
			(size 0.1397 0.1397)
			(layers "F.Cu" "F.Mask" "F.Paste")
			(net "FCB_HW_REVISION")
			(options
				(clearance outline)
				(anchor circle)
			)
			(primitives
				(gr_poly
					(pts
						(arc
							(start -0.1778 -0.2794)
							(mid -0.249642 -0.249642)
							(end -0.2794 -0.1778)
						)
						(arc
							(start -0.2794 0.1778)
							(mid -0.249642 0.249642)
							(end -0.1778 0.2794)
						)
						(arc
							(start 0.1778 0.2794)
							(mid 0.249642 0.249642)
							(end 0.2794 0.1778)
						)
						(arc
							(start 0.2794 -0.1778)
							(mid 0.249642 -0.249642)
							(end 0.1778 -0.2794)
						)
					)
					(width 0)
					(fill yes)
				)
			)
		)
		(pad "2" smd custom
			(at 0 0.4445)
			(size 0.1397 0.1397)
			(layers "F.Cu" "F.Mask" "F.Paste")
			(net "GND")
			(options
				(clearance outline)
				(anchor circle)
			)
			(primitives
				(gr_poly
					(pts
						(arc
							(start -0.1778 -0.2794)
							(mid -0.249642 -0.249642)
							(end -0.2794 -0.1778)
						)
						(arc
							(start -0.2794 0.1778)
							(mid -0.249642 0.249642)
							(end -0.1778 0.2794)
						)
						(arc
							(start 0.1778 0.2794)
							(mid 0.249642 0.249642)
							(end 0.2794 0.1778)
						)
						(arc
							(start 0.2794 -0.1778)
							(mid 0.249642 -0.249642)
							(end 0.1778 -0.2794)
						)
					)
					(width 0)
					(fill yes)
				)
			)
		)
	)
	(footprint ""
		(layer "F.Cu")
		(at 42.5958 -177.2666 180)
		(property "Reference" "PR47"
			(at 0 0 180)
			(layer "F.SilkS")
			(hide yes)
			(effects
				(font
					(size 1.27 1.27)
				)
			)
		)
		(property "Value" "4K7R2J-2-GP"
			(at 0.064008 -3.993896 180)
			(unlocked yes)
			(layer "F.Fab")
			(hide yes)
			(effects
				(font
					(size 1.016 1.016)
					(thickness 0.1524)
				)
			)
		)
		(property "Device Type" "R402H16"
			(at 0.064008 -5.517896 180)
			(unlocked yes)
			(layer "F.Fab")
			(hide yes)
			(effects
				(font
					(size 1.016 1.016)
					(thickness 0.1524)
				)
			)
		)
		(duplicate_pad_numbers_are_jumpers no)
		(fp_line
			(start 0.508 -0.9398)
			(end -0.508 -0.9398)
			(stroke
				(width 0.1524)
				(type default)
			)
			(layer "F.SilkS")
		)
		(fp_line
			(start -0.508 -0.9398)
			(end -0.508 0.9398)
			(stroke
				(width 0.1524)
				(type default)
			)
			(layer "F.SilkS")
		)
		(fp_rect
			(start -0.508 0.9398)
			(end 0.508 -0.9398)
			(stroke
				(width 0)
				(type default)
			)
			(fill no)
			(layer "F.CrtYd")
		)
		(fp_rect
			(start -0.508 0.9398)
			(end 0.508 -0.9398)
			(stroke
				(width 0)
				(type default)
			)
			(fill no)
			(layer "F.Fab")
		)
		(pad "1" smd custom
			(at 0 -0.4445 180)
			(size 0.1397 0.1397)
			(layers "F.Cu" "F.Mask" "F.Paste")
			(net "P3V3_AUX")
			(options
				(clearance outline)
				(anchor circle)
			)
			(primitives
				(gr_poly
					(pts
						(arc
							(start -0.1778 -0.2794)
							(mid -0.249642 -0.249642)
							(end -0.2794 -0.1778)
						)
						(arc
							(start -0.2794 0.1778)
							(mid -0.249642 0.249642)
							(end -0.1778 0.2794)
						)
						(arc
							(start 0.1778 0.2794)
							(mid 0.249642 0.249642)
							(end 0.2794 0.1778)
						)
						(arc
							(start 0.2794 -0.1778)
							(mid 0.249642 -0.249642)
							(end 0.1778 -0.2794)
						)
					)
					(width 0)
					(fill yes)
				)
			)
		)
		(pad "2" smd custom
			(at 0 0.4445 180)
			(size 0.1397 0.1397)
			(layers "F.Cu" "F.Mask" "F.Paste")
			(net "D_LATCH_Q")
			(options
				(clearance outline)
				(anchor circle)
			)
			(primitives
				(gr_poly
					(pts
						(arc
							(start -0.1778 -0.2794)
							(mid -0.249642 -0.249642)
							(end -0.2794 -0.1778)
						)
						(arc
							(start -0.2794 0.1778)
							(mid -0.249642 0.249642)
							(end -0.1778 0.2794)
						)
						(arc
							(start 0.1778 0.2794)
							(mid 0.249642 0.249642)
							(end 0.2794 0.1778)
						)
						(arc
							(start 0.2794 -0.1778)
							(mid 0.249642 -0.249642)
							(end 0.1778 -0.2794)
						)
					)
					(width 0)
					(fill yes)
				)
			)
		)
	)
	(footprint ""
		(layer "F.Cu")
		(at 29.1592 -253.8984 180)
		(property "Reference" "R45"
			(at 0 0 180)
			(layer "F.SilkS")
			(hide yes)
			(effects
				(font
					(size 1.27 1.27)
				)
			)
		)
		(property "Value" "0R2J-2-GP"
			(at 0.064008 -3.993896 180)
			(unlocked yes)
			(layer "F.Fab")
			(hide yes)
			(effects
				(font
					(size 1.016 1.016)
					(thickness 0.1524)
				)
			)
		)
		(property "Device Type" "R402H16"
			(at 0.064008 -5.517896 180)
			(unlocked yes)
			(layer "F.Fab")
			(hide yes)
			(effects
				(font
					(size 1.016 1.016)
					(thickness 0.1524)
				)
			)
		)
		(duplicate_pad_numbers_are_jumpers no)
		(fp_line
			(start 0.508 -0.9398)
			(end -0.508 -0.9398)
			(stroke
				(width 0.1524)
				(type default)
			)
			(layer "F.SilkS")
		)
		(fp_line
			(start -0.508 -0.9398)
			(end -0.508 0.9398)
			(stroke
				(width 0.1524)
				(type default)
			)
			(layer "F.SilkS")
		)
		(fp_rect
			(start -0.508 0.9398)
			(end 0.508 -0.9398)
			(stroke
				(width 0)
				(type default)
			)
			(fill no)
			(layer "F.CrtYd")
		)
		(fp_rect
			(start -0.508 0.9398)
			(end 0.508 -0.9398)
			(stroke
				(width 0)
				(type default)
			)
			(fill no)
			(layer "F.Fab")
		)
		(pad "1" smd custom
			(at 0 -0.4445 180)
			(size 0.1397 0.1397)
			(layers "F.Cu" "F.Mask" "F.Paste")
			(net "EEPROM_WP")
			(options
				(clearance outline)
				(anchor circle)
			)
			(primitives
				(gr_poly
					(pts
						(arc
							(start -0.1778 -0.2794)
							(mid -0.249642 -0.249642)
							(end -0.2794 -0.1778)
						)
						(arc
							(start -0.2794 0.1778)
							(mid -0.249642 0.249642)
							(end -0.1778 0.2794)
						)
						(arc
							(start 0.1778 0.2794)
							(mid 0.249642 0.249642)
							(end 0.2794 0.1778)
						)
						(arc
							(start 0.2794 -0.1778)
							(mid 0.249642 -0.249642)
							(end 0.1778 -0.2794)
						)
					)
					(width 0)
					(fill yes)
				)
			)
		)
		(pad "2" smd custom
			(at 0 0.4445 180)
			(size 0.1397 0.1397)
			(layers "F.Cu" "F.Mask" "F.Paste")
			(net "GND")
			(options
				(clearance outline)
				(anchor circle)
			)
			(primitives
				(gr_poly
					(pts
						(arc
							(start -0.1778 -0.2794)
							(mid -0.249642 -0.249642)
							(end -0.2794 -0.1778)
						)
						(arc
							(start -0.2794 0.1778)
							(mid -0.249642 0.249642)
							(end -0.1778 0.2794)
						)
						(arc
							(start 0.1778 0.2794)
							(mid 0.249642 0.249642)
							(end 0.2794 0.1778)
						)
						(arc
							(start 0.2794 -0.1778)
							(mid 0.249642 -0.249642)
							(end 0.1778 -0.2794)
						)
					)
					(width 0)
					(fill yes)
				)
			)
		)
	)
	(footprint ""
		(layer "F.Cu")
		(at 37.4904 -252.6284)
		(property "Reference" "TP26"
			(at 0 0 0)
			(layer "F.SilkS")
			(hide yes)
			(effects
				(font
					(size 1.27 1.27)
				)
			)
		)
		(property "Value" "TPAD32-GP"
			(at 0 -3.166364 0)
			(unlocked yes)
			(layer "F.Fab")
			(hide yes)
			(effects
				(font
					(size 1.016 1.016)
					(thickness 0.1524)
				)
			)
		)
		(property "Device Type" "TPAD32"
			(at 0 -4.690618 0)
			(unlocked yes)
			(layer "F.Fab")
			(hide yes)
			(effects
				(font
					(size 1.016 1.016)
					(thickness 0.1524)
				)
			)
		)
		(duplicate_pad_numbers_are_jumpers no)
		(fp_poly
			(pts
				(arc
					(start 0.7112 0)
					(mid -0.7112 0)
					(end 0.7112 0)
				)
			)
			(stroke
				(width 0)
				(type default)
			)
			(fill no)
			(layer "F.CrtYd")
		)
		(fp_poly
			(pts
				(arc
					(start 0.7112 0)
					(mid -0.7112 0)
					(end 0.7112 0)
				)
			)
			(stroke
				(width 0)
				(type default)
			)
			(fill no)
			(layer "F.Fab")
		)
		(pad "1" smd circle
			(at 0 0)
			(size 0.8128 0.8128)
			(layers "F.Cu" "F.Mask" "F.Paste")
			(net "LED_DR_LED7_RESERVE")
		)
	)
	(footprint ""
		(layer "F.Cu")
		(at 19.5834 -266.7254)
		(property "Reference" "F4"
			(at 0 0 0)
			(layer "F.SilkS")
			(hide yes)
			(effects
				(font
					(size 1.27 1.27)
				)
			)
		)
		(property "Value" "FUSE-3A15V-GP"
			(at 0.2286 -10.5918 0)
			(unlocked yes)
			(layer "F.Fab")
			(hide yes)
			(effects
				(font
					(size 1.016 1.016)
					(thickness 0.1524)
				)
			)
		)
		(property "Device Type" "FUSE-7452-UH50"
			(at 0.2286 -12.4968 0)
			(unlocked yes)
			(layer "F.Fab")
			(hide yes)
			(effects
				(font
					(size 1.016 1.016)
					(thickness 0.1524)
				)
			)
		)
		(duplicate_pad_numbers_are_jumpers no)
		(fp_line
			(start -4.9276 -2.921)
			(end 4.9276 -2.921)
			(stroke
				(width 0.1524)
				(type default)
			)
			(layer "F.SilkS")
		)
		(fp_line
			(start -4.9276 2.921)
			(end -4.9276 -2.921)
			(stroke
				(width 0.1524)
				(type default)
			)
			(layer "F.SilkS")
		)
		(fp_line
			(start 4.9276 -2.921)
			(end 4.9276 2.921)
			(stroke
				(width 0.1524)
				(type default)
			)
			(layer "F.SilkS")
		)
		(fp_line
			(start 4.9276 2.921)
			(end -4.9276 2.921)
			(stroke
				(width 0.1524)
				(type default)
			)
			(layer "F.SilkS")
		)
		(fp_poly
			(pts
				(xy -5.08 3.0988) (xy 5.08 3.0988) (xy 5.08 -3.0988) (xy -5.08 -3.0988)
			)
			(stroke
				(width 0)
				(type default)
			)
			(fill no)
			(layer "F.CrtYd")
		)
		(fp_poly
			(pts
				(xy -5.08 -3.0988) (xy 5.08 -3.0988) (xy 5.08 3.0988) (xy -5.08 3.0988)
			)
			(stroke
				(width 0)
				(type default)
			)
			(fill no)
			(layer "F.Fab")
		)
		(pad "1" smd rect
			(at -3.4036 0)
			(size 2.2098 5.2832)
			(layers "F.Cu" "F.Mask" "F.Paste")
			(net "P12V_FAN3")
		)
		(pad "2" smd rect
			(at 3.4036 0)
			(size 2.2098 5.2832)
			(layers "F.Cu" "F.Mask" "F.Paste")
			(net "P12V")
		)
	)
	(footprint ""
		(layer "F.Cu")
		(at 27.9654 -355.5238 90)
		(property "Reference" "Q10"
			(at 0 0 90)
			(layer "F.SilkS")
			(hide yes)
			(effects
				(font
					(size 1.27 1.27)
				)
			)
		)
		(property "Value" "2N7002DW-7F-GP"
			(at -2.3622 -8.2042 90)
			(unlocked yes)
			(layer "F.Fab")
			(hide yes)
			(effects
				(font
					(size 1.016 1.016)
					(thickness 0.1524)
				)
			)
		)
		(property "Device Type" "SOT-363H44"
			(at -2.3622 -10.1092 90)
			(unlocked yes)
			(layer "F.Fab")
			(hide yes)
			(effects
				(font
					(size 1.016 1.016)
					(thickness 0.1524)
				)
			)
		)
		(duplicate_pad_numbers_are_jumpers no)
		(fp_line
			(start 1.4478 -1.7018)
			(end -1.4478 -1.7018)
			(stroke
				(width 0.1524)
				(type default)
			)
			(layer "F.SilkS")
		)
		(fp_line
			(start -1.4478 -1.7018)
			(end -1.4478 1.7018)
			(stroke
				(width 0.1524)
				(type default)
			)
			(layer "F.SilkS")
		)
		(fp_line
			(start -1.27 1.524)
			(end -1.27 0.6604)
			(stroke
				(width 0.4826)
				(type default)
			)
			(layer "F.SilkS")
		)
		(fp_line
			(start 1.4478 1.7018)
			(end 1.4478 -1.7018)
			(stroke
				(width 0.1524)
				(type default)
			)
			(layer "F.SilkS")
		)
		(fp_line
			(start -1.4478 1.7018)
			(end 1.4478 1.7018)
			(stroke
				(width 0.1524)
				(type default)
			)
			(layer "F.SilkS")
		)
		(fp_poly
			(pts
				(xy -1.524 -1.778) (xy 1.524 -1.778) (xy 1.524 1.778) (xy -1.524 1.778)
			)
			(stroke
				(width 0)
				(type default)
			)
			(fill no)
			(layer "F.CrtYd")
		)
		(fp_poly
			(pts
				(xy -1.524 -1.778) (xy 1.524 -1.778) (xy 1.524 1.778) (xy -1.524 1.778)
			)
			(stroke
				(width 0)
				(type default)
			)
			(fill no)
			(layer "F.Fab")
		)
		(pad "1" smd rect
			(at -0.65024 0.9398 90)
			(size 0.4064 1.016)
			(layers "F.Cu" "F.Mask" "F.Paste")
			(net "GND")
		)
		(pad "2" smd rect
			(at 0 0.9398 90)
			(size 0.4064 1.016)
			(layers "F.Cu" "F.Mask" "F.Paste")
			(net "TEMP_ALM#")
		)
		(pad "3" smd rect
			(at 0.65024 0.9398 90)
			(size 0.4064 1.016)
			(layers "F.Cu" "F.Mask" "F.Paste")
			(net "TEMP_ALM#_JP_2")
		)
		(pad "4" smd rect
			(at 0.65024 -0.9398 90)
			(size 0.4064 1.016)
			(layers "F.Cu" "F.Mask" "F.Paste")
			(net "GND")
		)
		(pad "5" smd rect
			(at 0 -0.9398 90)
			(size 0.4064 1.016)
			(layers "F.Cu" "F.Mask" "F.Paste")
			(net "TEMP_ALM#_G")
		)
		(pad "6" smd rect
			(at -0.65024 -0.9398 90)
			(size 0.4064 1.016)
			(layers "F.Cu" "F.Mask" "F.Paste")
			(net "TEMP_ALM#_G")
		)
	)
)
